# S9S_MB_2U (Grand Teton) — schematic netlist excerpt (pin names and nets, part order shuffled) for the footprints in the layout excerpt that follows; sources: Cadence DE-HDL packaged netlist, KiCad conversion of 03242023_DA0F0TMBIJ0_F0T_Motherboard_J_brd_V01_OCP.brd

PC2950  Q_CAP  2.2UF 10V 10% X6S  pkg C0402  page 293 : A = PVCCFA_EHV_CPU1_PVCC ; B = GND
PC1192  Q_CAP  2.2UF 10V 10% X6S  pkg C0402  page 290 : A = PVCCFA_EHV_FIVRA_CPU1_VDD4 ; B = GND

(kicad_pcb
	(version 20260206)
	(generator "pcbnew")
	(generator_version "10.0")
	(general
		(thickness 1.6)
		(legacy_teardrops no)
	)
	(paper "A4")
	(title_block
		(title "03242023_DA0F0TMBIJ0_F0T_Motherboard_J_brd_V01_OCP.brd")
		(comment 1 "Grand Teton / footprints 2545-2546 of 6105")
	)
	(layers
		(0 "F.Cu" signal "TOP")
		(4 "In1.Cu" signal "GND")
		(6 "In2.Cu" signal "IN1")
		(8 "In3.Cu" signal "GND1")
		(10 "In4.Cu" signal "IN2")
		(12 "In5.Cu" signal "GND2")
		(14 "In6.Cu" signal "IN3")
		(16 "In7.Cu" signal "GND3")
		(18 "In8.Cu" signal "VCC")
		(20 "In9.Cu" signal "VCC1")
		(22 "In10.Cu" signal "GND4")
		(24 "In11.Cu" signal "IN4")
		(26 "In12.Cu" signal "GND5")
		(28 "In13.Cu" signal "IN5")
		(30 "In14.Cu" signal "GND6")
		(32 "In15.Cu" signal "IN6")
		(34 "In16.Cu" signal "GND7")
		(2 "B.Cu" signal "BOTTOM")
		(9 "F.Adhes" user "F.Adhesive")
		(11 "B.Adhes" user "B.Adhesive")
		(13 "F.Paste" user "Package Geometry/Pastemask Top")
		(15 "B.Paste" user "Package Geometry/Pastemask Bottom")
		(5 "F.SilkS" user "Ref Des/Silkscreen Top")
		(7 "B.SilkS" user "Ref Des/Silkscreen Bottom")
		(1 "F.Mask" user "Board Geometry/Soldermask Top")
		(3 "B.Mask" user "Board Geometry/Soldermask Bottom")
		(17 "Dwgs.User" user "User.Drawings")
		(19 "Cmts.User" user "User.Comments")
		(21 "Eco1.User" user "User.Eco1")
		(23 "Eco2.User" user "User.Eco2")
		(25 "Edge.Cuts" user "Board Geometry/Outline")
		(27 "Margin" user)
		(31 "F.CrtYd" user "Package Geometry/Place Bound Top")
		(29 "B.CrtYd" user "Package Geometry/Place Bound Bottom")
		(35 "F.Fab" user "Ref Des/Assembly Top")
		(33 "B.Fab" user "Ref Des/Assembly Bottom")
	)
	(footprint ""
		(layer "F.Cu")
		(at 55.090314 -152.903174)
		(property "Reference" "PC2950"
			(at 0 0 0)
			(layer "F.SilkS")
			(hide yes)
			(effects
				(font
					(size 1.27 1.27)
				)
			)
		)
		(property "Value" ""
			(at 0 0 0)
			(layer "F.Fab")
			(effects
				(font
					(size 1.27 1.27)
				)
			)
		)
		(duplicate_pad_numbers_are_jumpers no)
		(fp_line
			(start -0.7874 -0.4064)
			(end 0.7874 -0.4064)
			(stroke
				(width 0.1524)
				(type default)
			)
			(layer "F.SilkS")
		)
		(fp_line
			(start -0.7874 0.4064)
			(end -0.7874 -0.4064)
			(stroke
				(width 0.1524)
				(type default)
			)
			(layer "F.SilkS")
		)
		(fp_line
			(start 0.7874 -0.4064)
			(end 0.7874 0.4064)
			(stroke
				(width 0.1524)
				(type default)
			)
			(layer "F.SilkS")
		)
		(fp_line
			(start 0.7874 0.4064)
			(end -0.7874 0.4064)
			(stroke
				(width 0.1524)
				(type default)
			)
			(layer "F.SilkS")
		)
		(fp_line
			(start -0.67945 -0.305054)
			(end -0.12065 -0.305054)
			(stroke
				(width 0.1)
				(type default)
			)
			(layer "F.Fab")
		)
		(fp_line
			(start -0.67945 0.3048)
			(end -0.67945 -0.305054)
			(stroke
				(width 0.1)
				(type default)
			)
			(layer "F.Fab")
		)
		(fp_line
			(start -0.12065 -0.305054)
			(end -0.12065 -0.2794)
			(stroke
				(width 0.1)
				(type default)
			)
			(layer "F.Fab")
		)
		(fp_line
			(start -0.12065 -0.2794)
			(end 0.12065 -0.2794)
			(stroke
				(width 0.1)
				(type default)
			)
			(layer "F.Fab")
		)
		(fp_line
			(start -0.12065 0.2794)
			(end -0.12065 0.3048)
			(stroke
				(width 0.1)
				(type default)
			)
			(layer "F.Fab")
		)
		(fp_line
			(start -0.12065 0.3048)
			(end -0.67945 0.3048)
			(stroke
				(width 0.1)
				(type default)
			)
			(layer "F.Fab")
		)
		(fp_line
			(start 0.120396 0.2794)
			(end -0.12065 0.2794)
			(stroke
				(width 0.1)
				(type default)
			)
			(layer "F.Fab")
		)
		(fp_line
			(start 0.120396 0.3048)
			(end 0.120396 0.2794)
			(stroke
				(width 0.1)
				(type default)
			)
			(layer "F.Fab")
		)
		(fp_line
			(start 0.12065 -0.3048)
			(end 0.67945 -0.3048)
			(stroke
				(width 0.1)
				(type default)
			)
			(layer "F.Fab")
		)
		(fp_line
			(start 0.12065 -0.2794)
			(end 0.12065 -0.3048)
			(stroke
				(width 0.1)
				(type default)
			)
			(layer "F.Fab")
		)
		(fp_line
			(start 0.67945 -0.3048)
			(end 0.67945 0.3048)
			(stroke
				(width 0.1)
				(type default)
			)
			(layer "F.Fab")
		)
		(fp_line
			(start 0.67945 0.3048)
			(end 0.120396 0.3048)
			(stroke
				(width 0.1)
				(type default)
			)
			(layer "F.Fab")
		)
		(pad "1" smd circle
			(at -0.40005 0)
			(size 0 0)
			(layers "F.Cu" "F.Mask" "F.Paste")
			(net "PVCCFA_EHV_CPU1_PVCC")
		)
		(pad "2" smd circle
			(at 0.40005 0)
			(size 0 0)
			(layers "F.Cu" "F.Mask" "F.Paste")
			(net "GND")
		)
	)
	(footprint ""
		(layer "F.Cu")
		(at 37.990272 -356.02418 90)
		(property "Reference" "PC1192"
			(at 0 0 90)
			(layer "F.SilkS")
			(hide yes)
			(effects
				(font
					(size 1.27 1.27)
				)
			)
		)
		(property "Value" ""
			(at 0 0 90)
			(layer "F.Fab")
			(effects
				(font
					(size 1.27 1.27)
				)
			)
		)
		(duplicate_pad_numbers_are_jumpers no)
		(fp_line
			(start 0.7874 -0.4064)
			(end 0.7874 0.4064)
			(stroke
				(width 0.1524)
				(type default)
			)
			(layer "F.SilkS")
		)
		(fp_line
			(start -0.7874 -0.4064)
			(end 0.7874 -0.4064)
			(stroke
				(width 0.1524)
				(type default)
			)
			(layer "F.SilkS")
		)
		(fp_line
			(start 0.7874 0.4064)
			(end -0.7874 0.4064)
			(stroke
				(width 0.1524)
				(type default)
			)
			(layer "F.SilkS")
		)
		(fp_line
			(start -0.7874 0.4064)
			(end -0.7874 -0.4064)
			(stroke
				(width 0.1524)
				(type default)
			)
			(layer "F.SilkS")
		)
		(fp_line
			(start -0.12065 -0.305054)
			(end -0.12065 -0.2794)
			(stroke
				(width 0.1)
				(type default)
			)
			(layer "F.Fab")
		)
		(fp_line
			(start -0.67945 -0.305054)
			(end -0.12065 -0.305054)
			(stroke
				(width 0.1)
				(type default)
			)
			(layer "F.Fab")
		)
		(fp_line
			(start 0.67945 -0.3048)
			(end 0.67945 0.3048)
			(stroke
				(width 0.1)
				(type default)
			)
			(layer "F.Fab")
		)
		(fp_line
			(start 0.12065 -0.3048)
			(end 0.67945 -0.3048)
			(stroke
				(width 0.1)
				(type default)
			)
			(layer "F.Fab")
		)
		(fp_line
			(start 0.12065 -0.2794)
			(end 0.12065 -0.3048)
			(stroke
				(width 0.1)
				(type default)
			)
			(layer "F.Fab")
		)
		(fp_line
			(start -0.12065 -0.2794)
			(end 0.12065 -0.2794)
			(stroke
				(width 0.1)
				(type default)
			)
			(layer "F.Fab")
		)
		(fp_line
			(start 0.120396 0.2794)
			(end -0.12065 0.2794)
			(stroke
				(width 0.1)
				(type default)
			)
			(layer "F.Fab")
		)
		(fp_line
			(start -0.12065 0.2794)
			(end -0.12065 0.3048)
			(stroke
				(width 0.1)
				(type default)
			)
			(layer "F.Fab")
		)
		(fp_line
			(start 0.67945 0.3048)
			(end 0.120396 0.3048)
			(stroke
				(width 0.1)
				(type default)
			)
			(layer "F.Fab")
		)
		(fp_line
			(start 0.120396 0.3048)
			(end 0.120396 0.2794)
			(stroke
				(width 0.1)
				(type default)
			)
			(layer "F.Fab")
		)
		(fp_line
			(start -0.12065 0.3048)
			(end -0.67945 0.3048)
			(stroke
				(width 0.1)
				(type default)
			)
			(layer "F.Fab")
		)
		(fp_line
			(start -0.67945 0.3048)
			(end -0.67945 -0.305054)
			(stroke
				(width 0.1)
				(type default)
			)
			(layer "F.Fab")
		)
		(pad "1" smd circle
			(at -0.40005 0 90)
			(size 0 0)
			(layers "F.Cu" "F.Mask" "F.Paste")
			(net "PVCCFA_EHV_FIVRA_CPU1_VDD4")
		)
		(pad "2" smd circle
			(at 0.40005 0 90)
			(size 0 0)
			(layers "F.Cu" "F.Mask" "F.Paste")
			(net "GND")
		)
	)
)
